(kicad_pcb
	(version 20260206)
	(generator "pcbnew")
	(generator_version "10.0")
	(general
		(thickness 1.6)
		(legacy_teardrops no)
	)
	(paper "A4")
	(title_block
		(title "Bryce Canyon_SCC_16316-1_OCP.brd")
		(comment 1 "Bryce Canyon / footprints 734-741 of 1561")
	)
	(layers
		(0 "F.Cu" signal "TOP")
		(4 "In1.Cu" signal "L2GND")
		(6 "In2.Cu" signal "L3")
		(8 "In3.Cu" signal "L4VCC")
		(10 "In4.Cu" signal "L5VCC")
		(12 "In5.Cu" signal "L6")
		(14 "In6.Cu" signal "L7GND")
		(2 "B.Cu" signal "BOTTOM")
		(9 "F.Adhes" user "F.Adhesive")
		(11 "B.Adhes" user "B.Adhesive")
		(13 "F.Paste" user "Package Geometry/Pastemask Top")
		(15 "B.Paste" user "Package Geometry/Pastemask Bottom")
		(5 "F.SilkS" user "Ref Des/Silkscreen Top")
		(7 "B.SilkS" user "Ref Des/Silkscreen Bottom")
		(1 "F.Mask" user "Board Geometry/Soldermask Top")
		(3 "B.Mask" user "Board Geometry/Soldermask Bottom")
		(17 "Dwgs.User" user "User.Drawings")
		(19 "Cmts.User" user "User.Comments")
		(21 "Eco1.User" user "User.Eco1")
		(23 "Eco2.User" user "User.Eco2")
		(25 "Edge.Cuts" user "Board Geometry/Outline")
		(27 "Margin" user)
		(31 "F.CrtYd" user "Package Geometry/Place Bound Top")
		(29 "B.CrtYd" user "Package Geometry/Place Bound Bottom")
		(35 "F.Fab" user "Ref Des/Assembly Top")
		(33 "B.Fab" user "Ref Des/Assembly Bottom")
	)
	(footprint ""
		(layer "F.Cu")
		(at 80.7847 -74.9046 180)
		(property "Reference" "R94"
			(at 0 0 180)
			(layer "F.SilkS")
			(hide yes)
			(effects
				(font
					(size 1.27 1.27)
				)
			)
		)
		(property "Value" "150R2F-1-GP"
			(at 0.064008 -3.993896 180)
			(unlocked yes)
			(layer "F.Fab")
			(hide yes)
			(effects
				(font
					(size 1.016 1.016)
					(thickness 0.1524)
				)
			)
		)
		(property "Device Type" "R402H16"
			(at 0.064008 -5.517896 180)
			(unlocked yes)
			(layer "F.Fab")
			(hide yes)
			(effects
				(font
					(size 1.016 1.016)
					(thickness 0.1524)
				)
			)
		)
		(duplicate_pad_numbers_are_jumpers no)
		(fp_line
			(start 0.508 -0.9398)
			(end -0.508 -0.9398)
			(stroke
				(width 0.1524)
				(type default)
			)
			(layer "F.SilkS")
		)
		(fp_line
			(start -0.508 -0.9398)
			(end -0.508 0.9398)
			(stroke
				(width 0.1524)
				(type default)
			)
			(layer "F.SilkS")
		)
		(fp_rect
			(start -0.508 0.9398)
			(end 0.508 -0.9398)
			(stroke
				(width 0)
				(type default)
			)
			(fill no)
			(layer "F.CrtYd")
		)
		(fp_rect
			(start -0.508 0.9398)
			(end 0.508 -0.9398)
			(stroke
				(width 0)
				(type default)
			)
			(fill no)
			(layer "F.Fab")
		)
		(pad "1" smd custom
			(at 0 -0.4445 180)
			(size 0.1397 0.1397)
			(layers "F.Cu" "F.Mask" "F.Paste")
			(net "P3V3")
			(options
				(clearance outline)
				(anchor circle)
			)
			(primitives
				(gr_poly
					(pts
						(arc
							(start -0.1778 -0.2794)
							(mid -0.249642 -0.249642)
							(end -0.2794 -0.1778)
						)
						(arc
							(start -0.2794 0.1778)
							(mid -0.249642 0.249642)
							(end -0.1778 0.2794)
						)
						(arc
							(start 0.1778 0.2794)
							(mid 0.249642 0.249642)
							(end 0.2794 0.1778)
						)
						(arc
							(start 0.2794 -0.1778)
							(mid 0.249642 -0.249642)
							(end 0.1778 -0.2794)
						)
					)
					(width 0)
					(fill yes)
				)
			)
		)
		(pad "2" smd custom
			(at 0 0.4445 180)
			(size 0.1397 0.1397)
			(layers "F.Cu" "F.Mask" "F.Paste")
			(net "EXP_HW_LED_R")
			(options
				(clearance outline)
				(anchor circle)
			)
			(primitives
				(gr_poly
					(pts
						(arc
							(start -0.1778 -0.2794)
							(mid -0.249642 -0.249642)
							(end -0.2794 -0.1778)
						)
						(arc
							(start -0.2794 0.1778)
							(mid -0.249642 0.249642)
							(end -0.1778 0.2794)
						)
						(arc
							(start 0.1778 0.2794)
							(mid 0.249642 0.249642)
							(end 0.2794 0.1778)
						)
						(arc
							(start 0.2794 -0.1778)
							(mid 0.249642 -0.249642)
							(end 0.1778 -0.2794)
						)
					)
					(width 0)
					(fill yes)
				)
			)
		)
	)
	(footprint ""
		(layer "F.Cu")
		(at 43.0022 -43.4086)
		(property "Reference" "C666"
			(at 0 0 0)
			(layer "F.SilkS")
			(hide yes)
			(effects
				(font
					(size 1.27 1.27)
				)
			)
		)
		(property "Value" "SC10U16V5KX-7-GP-U"
			(at -0.0762 -6.1214 0)
			(unlocked yes)
			(layer "F.Fab")
			(hide yes)
			(effects
				(font
					(size 1.016 1.016)
					(thickness 0.1524)
				)
			)
		)
		(property "Device Type" "C805H58"
			(at -0.0762 -8.1534 0)
			(unlocked yes)
			(layer "F.Fab")
			(hide yes)
			(effects
				(font
					(size 1.016 1.016)
					(thickness 0.1524)
				)
			)
		)
		(duplicate_pad_numbers_are_jumpers no)
		(fp_line
			(start 0.635 0)
			(end -0.635 0)
			(stroke
				(width 0.508)
				(type default)
			)
			(layer "F.SilkS")
		)
		(fp_rect
			(start -0.9652 1.778)
			(end 0.9652 -1.778)
			(stroke
				(width 0)
				(type default)
			)
			(fill no)
			(layer "F.CrtYd")
		)
		(fp_poly
			(pts
				(xy -0.9652 -1.778) (xy 0.9652 -1.778) (xy 0.9652 1.778) (xy -0.9652 1.778)
			)
			(stroke
				(width 0)
				(type default)
			)
			(fill no)
			(layer "F.Fab")
		)
		(pad "1" smd rect
			(at 0 -0.9652)
			(size 1.397 1.143)
			(layers "F.Cu" "F.Mask" "F.Paste")
			(net "P12V_STBY_VIN_Q7")
		)
		(pad "2" smd rect
			(at 0 0.9652)
			(size 1.397 1.143)
			(layers "F.Cu" "F.Mask" "F.Paste")
			(net "GND")
		)
	)
	(footprint ""
		(layer "F.Cu")
		(at 19.177 -59.1312)
		(property "Reference" "R536"
			(at 0 0 0)
			(layer "F.SilkS")
			(hide yes)
			(effects
				(font
					(size 1.27 1.27)
				)
			)
		)
		(property "Value" "0R2J-2-GP"
			(at 0.064008 -3.993896 0)
			(unlocked yes)
			(layer "F.Fab")
			(hide yes)
			(effects
				(font
					(size 1.016 1.016)
					(thickness 0.1524)
				)
			)
		)
		(property "Device Type" "R402H16"
			(at 0.064008 -5.517896 0)
			(unlocked yes)
			(layer "F.Fab")
			(hide yes)
			(effects
				(font
					(size 1.016 1.016)
					(thickness 0.1524)
				)
			)
		)
		(duplicate_pad_numbers_are_jumpers no)
		(fp_line
			(start -0.508 -0.9398)
			(end -0.508 0.9398)
			(stroke
				(width 0.1524)
				(type default)
			)
			(layer "F.SilkS")
		)
		(fp_line
			(start 0.508 -0.9398)
			(end -0.508 -0.9398)
			(stroke
				(width 0.1524)
				(type default)
			)
			(layer "F.SilkS")
		)
		(fp_rect
			(start -0.508 0.9398)
			(end 0.508 -0.9398)
			(stroke
				(width 0)
				(type default)
			)
			(fill no)
			(layer "F.CrtYd")
		)
		(fp_rect
			(start -0.508 0.9398)
			(end 0.508 -0.9398)
			(stroke
				(width 0)
				(type default)
			)
			(fill no)
			(layer "F.Fab")
		)
		(pad "1" smd custom
			(at 0 -0.4445)
			(size 0.1397 0.1397)
			(layers "F.Cu" "F.Mask" "F.Paste")
			(net "AGND_CURRENT_MON")
			(options
				(clearance outline)
				(anchor circle)
			)
			(primitives
				(gr_poly
					(pts
						(arc
							(start -0.1778 -0.2794)
							(mid -0.249642 -0.249642)
							(end -0.2794 -0.1778)
						)
						(arc
							(start -0.2794 0.1778)
							(mid -0.249642 0.249642)
							(end -0.1778 0.2794)
						)
						(arc
							(start 0.1778 0.2794)
							(mid 0.249642 0.249642)
							(end 0.2794 0.1778)
						)
						(arc
							(start 0.2794 -0.1778)
							(mid 0.249642 -0.249642)
							(end 0.1778 -0.2794)
						)
					)
					(width 0)
					(fill yes)
				)
			)
		)
		(pad "2" smd custom
			(at 0 0.4445)
			(size 0.1397 0.1397)
			(layers "F.Cu" "F.Mask" "F.Paste")
			(net "MB0_CM_ADR1_R")
			(options
				(clearance outline)
				(anchor circle)
			)
			(primitives
				(gr_poly
					(pts
						(arc
							(start -0.1778 -0.2794)
							(mid -0.249642 -0.249642)
							(end -0.2794 -0.1778)
						)
						(arc
							(start -0.2794 0.1778)
							(mid -0.249642 0.249642)
							(end -0.1778 0.2794)
						)
						(arc
							(start 0.1778 0.2794)
							(mid 0.249642 0.249642)
							(end 0.2794 0.1778)
						)
						(arc
							(start 0.2794 -0.1778)
							(mid 0.249642 -0.249642)
							(end 0.1778 -0.2794)
						)
					)
					(width 0)
					(fill yes)
				)
			)
		)
	)
	(footprint ""
		(layer "F.Cu")
		(at 194.01536 -67.31254 180)
		(property "Reference" "R299"
			(at 0 0 180)
			(layer "F.SilkS")
			(hide yes)
			(effects
				(font
					(size 1.27 1.27)
				)
			)
		)
		(property "Value" "0R2J-2-GP"
			(at 0.064008 -3.993896 180)
			(unlocked yes)
			(layer "F.Fab")
			(hide yes)
			(effects
				(font
					(size 1.016 1.016)
					(thickness 0.1524)
				)
			)
		)
		(property "Device Type" "R402H16"
			(at 0.064008 -5.517896 180)
			(unlocked yes)
			(layer "F.Fab")
			(hide yes)
			(effects
				(font
					(size 1.016 1.016)
					(thickness 0.1524)
				)
			)
		)
		(duplicate_pad_numbers_are_jumpers no)
		(fp_line
			(start 0.508 -0.9398)
			(end -0.508 -0.9398)
			(stroke
				(width 0.1524)
				(type default)
			)
			(layer "F.SilkS")
		)
		(fp_line
			(start -0.508 -0.9398)
			(end -0.508 0.9398)
			(stroke
				(width 0.1524)
				(type default)
			)
			(layer "F.SilkS")
		)
		(fp_rect
			(start -0.508 0.9398)
			(end 0.508 -0.9398)
			(stroke
				(width 0)
				(type default)
			)
			(fill no)
			(layer "F.CrtYd")
		)
		(fp_rect
			(start -0.508 0.9398)
			(end 0.508 -0.9398)
			(stroke
				(width 0)
				(type default)
			)
			(fill no)
			(layer "F.Fab")
		)
		(pad "1" smd custom
			(at 0 -0.4445 180)
			(size 0.1397 0.1397)
			(layers "F.Cu" "F.Mask" "F.Paste")
			(net "UART_IOC_RX")
			(options
				(clearance outline)
				(anchor circle)
			)
			(primitives
				(gr_poly
					(pts
						(arc
							(start -0.1778 -0.2794)
							(mid -0.249642 -0.249642)
							(end -0.2794 -0.1778)
						)
						(arc
							(start -0.2794 0.1778)
							(mid -0.249642 0.249642)
							(end -0.1778 0.2794)
						)
						(arc
							(start 0.1778 0.2794)
							(mid 0.249642 0.249642)
							(end 0.2794 0.1778)
						)
						(arc
							(start 0.2794 -0.1778)
							(mid 0.249642 -0.249642)
							(end 0.1778 -0.2794)
						)
					)
					(width 0)
					(fill yes)
				)
			)
		)
		(pad "2" smd custom
			(at 0 0.4445 180)
			(size 0.1397 0.1397)
			(layers "F.Cu" "F.Mask" "F.Paste")
			(net "IOC_UART_R_RX")
			(options
				(clearance outline)
				(anchor circle)
			)
			(primitives
				(gr_poly
					(pts
						(arc
							(start -0.1778 -0.2794)
							(mid -0.249642 -0.249642)
							(end -0.2794 -0.1778)
						)
						(arc
							(start -0.2794 0.1778)
							(mid -0.249642 0.249642)
							(end -0.1778 0.2794)
						)
						(arc
							(start 0.1778 0.2794)
							(mid 0.249642 0.249642)
							(end 0.2794 0.1778)
						)
						(arc
							(start 0.2794 -0.1778)
							(mid 0.249642 -0.249642)
							(end 0.1778 -0.2794)
						)
					)
					(width 0)
					(fill yes)
				)
			)
		)
	)
	(footprint ""
		(layer "F.Cu")
		(at 74.4474 -83.3882 90)
		(property "Reference" "C598"
			(at 0 0 90)
			(layer "F.SilkS")
			(hide yes)
			(effects
				(font
					(size 1.27 1.27)
				)
			)
		)
		(property "Value" "SCD1U16V2KX-3GP"
			(at 1.1811 -2.7051 90)
			(unlocked yes)
			(layer "F.Fab")
			(hide yes)
			(effects
				(font
					(size 1.016 1.016)
					(thickness 0.1524)
				)
			)
		)
		(property "Device Type" "C402H22"
			(at 1.1811 -4.2291 90)
			(unlocked yes)
			(layer "F.Fab")
			(hide yes)
			(effects
				(font
					(size 1.016 1.016)
					(thickness 0.1524)
				)
			)
		)
		(duplicate_pad_numbers_are_jumpers no)
		(fp_rect
			(start -0.4318 0.9525)
			(end 0.4318 -0.9525)
			(stroke
				(width 0)
				(type default)
			)
			(fill no)
			(layer "F.CrtYd")
		)
		(fp_rect
			(start -0.4318 0.9525)
			(end 0.4318 -0.9525)
			(stroke
				(width 0)
				(type default)
			)
			(fill no)
			(layer "F.Fab")
		)
		(pad "1" smd custom
			(at 0 -0.4445 90)
			(size 0.1524 0.1524)
			(layers "F.Cu" "F.Mask" "F.Paste")
			(net "P1V8_E")
			(options
				(clearance outline)
				(anchor circle)
			)
			(primitives
				(gr_poly
					(pts
						(arc
							(start 0.3048 -0.2032)
							(mid 0.275042 -0.275042)
							(end 0.2032 -0.3048)
						)
						(arc
							(start -0.2032 -0.3048)
							(mid -0.275042 -0.275042)
							(end -0.3048 -0.2032)
						)
						(arc
							(start -0.3048 0.2032)
							(mid -0.275042 0.275042)
							(end -0.2032 0.3048)
						)
						(arc
							(start 0.2032 0.3048)
							(mid 0.275042 0.275042)
							(end 0.3048 0.2032)
						)
					)
					(width 0)
					(fill yes)
				)
			)
		)
		(pad "2" smd custom
			(at 0 0.4445 90)
			(size 0.1524 0.1524)
			(layers "F.Cu" "F.Mask" "F.Paste")
			(net "GND")
			(options
				(clearance outline)
				(anchor circle)
			)
			(primitives
				(gr_poly
					(pts
						(arc
							(start 0.3048 -0.2032)
							(mid 0.275042 -0.275042)
							(end 0.2032 -0.3048)
						)
						(arc
							(start -0.2032 -0.3048)
							(mid -0.275042 -0.275042)
							(end -0.3048 -0.2032)
						)
						(arc
							(start -0.3048 0.2032)
							(mid -0.275042 0.275042)
							(end -0.2032 0.3048)
						)
						(arc
							(start 0.2032 0.3048)
							(mid 0.275042 0.275042)
							(end 0.3048 0.2032)
						)
					)
					(width 0)
					(fill yes)
				)
			)
		)
	)
	(footprint ""
		(layer "F.Cu")
		(at 171.661074 -100.160582 180)
		(property "Reference" "R495"
			(at 0 0 180)
			(layer "F.SilkS")
			(hide yes)
			(effects
				(font
					(size 1.27 1.27)
				)
			)
		)
		(property "Value" "100KR2F-L1-GP"
			(at 0.064008 -3.993896 180)
			(unlocked yes)
			(layer "F.Fab")
			(hide yes)
			(effects
				(font
					(size 1.016 1.016)
					(thickness 0.1524)
				)
			)
		)
		(property "Device Type" "R402H16"
			(at 0.064008 -5.517896 180)
			(unlocked yes)
			(layer "F.Fab")
			(hide yes)
			(effects
				(font
					(size 1.016 1.016)
					(thickness 0.1524)
				)
			)
		)
		(duplicate_pad_numbers_are_jumpers no)
		(fp_line
			(start 0.508 -0.9398)
			(end -0.508 -0.9398)
			(stroke
				(width 0.1524)
				(type default)
			)
			(layer "F.SilkS")
		)
		(fp_line
			(start -0.508 -0.9398)
			(end -0.508 0.9398)
			(stroke
				(width 0.1524)
				(type default)
			)
			(layer "F.SilkS")
		)
		(fp_rect
			(start -0.508 0.9398)
			(end 0.508 -0.9398)
			(stroke
				(width 0)
				(type default)
			)
			(fill no)
			(layer "F.CrtYd")
		)
		(fp_rect
			(start -0.508 0.9398)
			(end 0.508 -0.9398)
			(stroke
				(width 0)
				(type default)
			)
			(fill no)
			(layer "F.Fab")
		)
		(pad "1" smd custom
			(at 0 -0.4445 180)
			(size 0.1397 0.1397)
			(layers "F.Cu" "F.Mask" "F.Paste")
			(net "VT235_VDES")
			(options
				(clearance outline)
				(anchor circle)
			)
			(primitives
				(gr_poly
					(pts
						(arc
							(start -0.1778 -0.2794)
							(mid -0.249642 -0.249642)
							(end -0.2794 -0.1778)
						)
						(arc
							(start -0.2794 0.1778)
							(mid -0.249642 0.249642)
							(end -0.1778 0.2794)
						)
						(arc
							(start 0.1778 0.2794)
							(mid 0.249642 0.249642)
							(end 0.2794 0.1778)
						)
						(arc
							(start 0.2794 -0.1778)
							(mid 0.249642 -0.249642)
							(end 0.1778 -0.2794)
						)
					)
					(width 0)
					(fill yes)
				)
			)
		)
		(pad "2" smd custom
			(at 0 0.4445 180)
			(size 0.1397 0.1397)
			(layers "F.Cu" "F.Mask" "F.Paste")
			(net "VT235_VREF")
			(options
				(clearance outline)
				(anchor circle)
			)
			(primitives
				(gr_poly
					(pts
						(arc
							(start -0.1778 -0.2794)
							(mid -0.249642 -0.249642)
							(end -0.2794 -0.1778)
						)
						(arc
							(start -0.2794 0.1778)
							(mid -0.249642 0.249642)
							(end -0.1778 0.2794)
						)
						(arc
							(start 0.1778 0.2794)
							(mid 0.249642 0.249642)
							(end 0.2794 0.1778)
						)
						(arc
							(start 0.2794 -0.1778)
							(mid 0.249642 -0.249642)
							(end 0.1778 -0.2794)
						)
					)
					(width 0)
					(fill yes)
				)
			)
		)
	)
	(footprint ""
		(layer "F.Cu")
		(at 148.0058 -116.9162 -90)
		(property "Reference" "R372"
			(at 0 0 270)
			(layer "F.SilkS")
			(hide yes)
			(effects
				(font
					(size 1.27 1.27)
				)
			)
		)
		(property "Value" "0R2J-2-GP"
			(at 0.064008 -3.993896 270)
			(unlocked yes)
			(layer "F.Fab")
			(hide yes)
			(effects
				(font
					(size 1.016 1.016)
					(thickness 0.1524)
				)
			)
		)
		(property "Device Type" "R402H16"
			(at 0.064008 -5.517896 270)
			(unlocked yes)
			(layer "F.Fab")
			(hide yes)
			(effects
				(font
					(size 1.016 1.016)
					(thickness 0.1524)
				)
			)
		)
		(duplicate_pad_numbers_are_jumpers no)
		(fp_line
			(start -0.508 -0.9398)
			(end -0.508 0.9398)
			(stroke
				(width 0.1524)
				(type default)
			)
			(layer "F.SilkS")
		)
		(fp_line
			(start 0.508 -0.9398)
			(end -0.508 -0.9398)
			(stroke
				(width 0.1524)
				(type default)
			)
			(layer "F.SilkS")
		)
		(fp_rect
			(start -0.508 0.9398)
			(end 0.508 -0.9398)
			(stroke
				(width 0)
				(type default)
			)
			(fill no)
			(layer "F.CrtYd")
		)
		(fp_rect
			(start -0.508 0.9398)
			(end 0.508 -0.9398)
			(stroke
				(width 0)
				(type default)
			)
			(fill no)
			(layer "F.Fab")
		)
		(pad "1" smd custom
			(at 0 -0.4445 270)
			(size 0.1397 0.1397)
			(layers "F.Cu" "F.Mask" "F.Paste")
			(net "P1V5_E_ROVP")
			(options
				(clearance outline)
				(anchor circle)
			)
			(primitives
				(gr_poly
					(pts
						(arc
							(start -0.1778 -0.2794)
							(mid -0.249642 -0.249642)
							(end -0.2794 -0.1778)
						)
						(arc
							(start -0.2794 0.1778)
							(mid -0.249642 0.249642)
							(end -0.1778 0.2794)
						)
						(arc
							(start 0.1778 0.2794)
							(mid 0.249642 0.249642)
							(end 0.2794 0.1778)
						)
						(arc
							(start 0.2794 -0.1778)
							(mid 0.249642 -0.249642)
							(end 0.1778 -0.2794)
						)
					)
					(width 0)
					(fill yes)
				)
			)
		)
		(pad "2" smd custom
			(at 0 0.4445 270)
			(size 0.1397 0.1397)
			(layers "F.Cu" "F.Mask" "F.Paste")
			(net "AGND_P1V5_E")
			(options
				(clearance outline)
				(anchor circle)
			)
			(primitives
				(gr_poly
					(pts
						(arc
							(start -0.1778 -0.2794)
							(mid -0.249642 -0.249642)
							(end -0.2794 -0.1778)
						)
						(arc
							(start -0.2794 0.1778)
							(mid -0.249642 0.249642)
							(end -0.1778 0.2794)
						)
						(arc
							(start 0.1778 0.2794)
							(mid 0.249642 0.249642)
							(end 0.2794 0.1778)
						)
						(arc
							(start 0.2794 -0.1778)
							(mid 0.249642 -0.249642)
							(end 0.1778 -0.2794)
						)
					)
					(width 0)
					(fill yes)
				)
			)
		)
	)
	(footprint ""
		(layer "F.Cu")
		(at 175.3362 -79.5528 -90)
		(property "Reference" "C383"
			(at 0 0 270)
			(layer "F.SilkS")
			(hide yes)
			(effects
				(font
					(size 1.27 1.27)
				)
			)
		)
		(property "Value" "SC100U6D3V6MX-GP"
			(at -0.0762 -5.1308 270)
			(unlocked yes)
			(layer "F.Fab")
			(hide yes)
			(effects
				(font
					(size 1.016 1.016)
					(thickness 0.1524)
				)
			)
		)
		(property "Device Type" "C1206H71"
			(at -0.127 -6.6548 270)
			(unlocked yes)
			(layer "F.Fab")
			(hide yes)
			(effects
				(font
					(size 1.016 1.016)
					(thickness 0.1524)
				)
			)
		)
		(duplicate_pad_numbers_are_jumpers no)
		(fp_line
			(start -1.016 2.2352)
			(end -1.016 0.8382)
			(stroke
				(width 0.1524)
				(type default)
			)
			(layer "F.SilkS")
		)
		(fp_line
			(start 1.016 2.2352)
			(end -1.016 2.2352)
			(stroke
				(width 0.1524)
				(type default)
			)
			(layer "F.SilkS")
		)
		(fp_line
			(start 1.016 0.8382)
			(end 1.016 2.2352)
			(stroke
				(width 0.1524)
				(type default)
			)
			(layer "F.SilkS")
		)
		(fp_line
			(start -1.016 -0.8382)
			(end -1.016 -2.2352)
			(stroke
				(width 0.1524)
				(type default)
			)
			(layer "F.SilkS")
		)
		(fp_line
			(start -1.016 -2.2352)
			(end 1.016 -2.2352)
			(stroke
				(width 0.1524)
				(type default)
			)
			(layer "F.SilkS")
		)
		(fp_line
			(start 1.016 -2.2352)
			(end 1.016 -0.8382)
			(stroke
				(width 0.1524)
				(type default)
			)
			(layer "F.SilkS")
		)
		(fp_rect
			(start -1.0922 2.3114)
			(end 1.0922 -2.3114)
			(stroke
				(width 0)
				(type default)
			)
			(fill no)
			(layer "F.CrtYd")
		)
		(fp_poly
			(pts
				(xy 1.0922 -2.3114) (xy 1.0922 2.3114) (xy -1.0922 2.3114) (xy -1.0922 -2.3114)
			)
			(stroke
				(width 0)
				(type default)
			)
			(fill no)
			(layer "F.Fab")
		)
		(pad "1" smd rect
			(at 0 -1.397 270)
			(size 1.651 1.27)
			(layers "F.Cu" "F.Mask" "F.Paste")
			(net "GND")
		)
		(pad "2" smd rect
			(at 0 1.397 270)
			(size 1.651 1.27)
			(layers "F.Cu" "F.Mask" "F.Paste")
			(net "PCE_AVDD")
		)
	)
)
